# S9S_MB_2U (Grand Teton) — schematic netlist excerpt (pin names and nets, part order shuffled) for the footprints in the layout excerpt that follows; sources: Cadence DE-HDL packaged netlist, KiCad conversion of 03242023_DA0F0TMBIJ0_F0T_Motherboard_J_brd_V01_OCP.brd

R3265  Q_RES  4.7K 1% EMPTY  pkg 0402LF  page 166 : A = CLK_GEN2_GPU_FPGA_OE_OR_N ; B = GND
R1390  Q_RES  1K 1% EMPTY  pkg 0402LF  page 208 : A = FM_PLD_CLKS_DEV_EN ; B = GND

(kicad_pcb
	(version 20260206)
	(generator "pcbnew")
	(generator_version "10.0")
	(general
		(thickness 1.6)
		(legacy_teardrops no)
	)
	(paper "A4")
	(title_block
		(title "03242023_DA0F0TMBIJ0_F0T_Motherboard_J_brd_V01_OCP.brd")
		(comment 1 "Grand Teton / footprints 3571-3572 of 6105")
	)
	(layers
		(0 "F.Cu" signal "TOP")
		(4 "In1.Cu" signal "GND")
		(6 "In2.Cu" signal "IN1")
		(8 "In3.Cu" signal "GND1")
		(10 "In4.Cu" signal "IN2")
		(12 "In5.Cu" signal "GND2")
		(14 "In6.Cu" signal "IN3")
		(16 "In7.Cu" signal "GND3")
		(18 "In8.Cu" signal "VCC")
		(20 "In9.Cu" signal "VCC1")
		(22 "In10.Cu" signal "GND4")
		(24 "In11.Cu" signal "IN4")
		(26 "In12.Cu" signal "GND5")
		(28 "In13.Cu" signal "IN5")
		(30 "In14.Cu" signal "GND6")
		(32 "In15.Cu" signal "IN6")
		(34 "In16.Cu" signal "GND7")
		(2 "B.Cu" signal "BOTTOM")
		(9 "F.Adhes" user "F.Adhesive")
		(11 "B.Adhes" user "B.Adhesive")
		(13 "F.Paste" user "Package Geometry/Pastemask Top")
		(15 "B.Paste" user "Package Geometry/Pastemask Bottom")
		(5 "F.SilkS" user "Ref Des/Silkscreen Top")
		(7 "B.SilkS" user "Ref Des/Silkscreen Bottom")
		(1 "F.Mask" user "Board Geometry/Soldermask Top")
		(3 "B.Mask" user "Board Geometry/Soldermask Bottom")
		(17 "Dwgs.User" user "User.Drawings")
		(19 "Cmts.User" user "User.Comments")
		(21 "Eco1.User" user "User.Eco1")
		(23 "Eco2.User" user "User.Eco2")
		(25 "Edge.Cuts" user "Board Geometry/Outline")
		(27 "Margin" user)
		(31 "F.CrtYd" user "Package Geometry/Place Bound Top")
		(29 "B.CrtYd" user "Package Geometry/Place Bound Bottom")
		(35 "F.Fab" user "Ref Des/Assembly Top")
		(33 "B.Fab" user "Ref Des/Assembly Bottom")
	)
	(footprint ""
		(layer "F.Cu")
		(at 27.628596 -387.246876)
		(property "Reference" "R3265"
			(at 0 0 0)
			(layer "F.SilkS")
			(hide yes)
			(effects
				(font
					(size 1.27 1.27)
				)
			)
		)
		(property "Value" ""
			(at 0 0 0)
			(layer "F.Fab")
			(effects
				(font
					(size 1.27 1.27)
				)
			)
		)
		(duplicate_pad_numbers_are_jumpers no)
		(fp_line
			(start -0.7874 -0.4064)
			(end 0.7874 -0.4064)
			(stroke
				(width 0.1524)
				(type default)
			)
			(layer "F.SilkS")
		)
		(fp_line
			(start -0.7874 0.4064)
			(end -0.7874 -0.4064)
			(stroke
				(width 0.1524)
				(type default)
			)
			(layer "F.SilkS")
		)
		(fp_line
			(start 0.7874 -0.4064)
			(end 0.7874 0.4064)
			(stroke
				(width 0.1524)
				(type default)
			)
			(layer "F.SilkS")
		)
		(fp_line
			(start 0.7874 0.4064)
			(end -0.7874 0.4064)
			(stroke
				(width 0.1524)
				(type default)
			)
			(layer "F.SilkS")
		)
		(fp_line
			(start -0.67945 -0.305054)
			(end -0.12065 -0.305054)
			(stroke
				(width 0.1)
				(type default)
			)
			(layer "F.Fab")
		)
		(fp_line
			(start -0.67945 0.3048)
			(end -0.67945 -0.305054)
			(stroke
				(width 0.1)
				(type default)
			)
			(layer "F.Fab")
		)
		(fp_line
			(start -0.12065 -0.305054)
			(end -0.12065 -0.2794)
			(stroke
				(width 0.1)
				(type default)
			)
			(layer "F.Fab")
		)
		(fp_line
			(start -0.12065 -0.2794)
			(end 0.12065 -0.2794)
			(stroke
				(width 0.1)
				(type default)
			)
			(layer "F.Fab")
		)
		(fp_line
			(start -0.12065 0.2794)
			(end -0.12065 0.3048)
			(stroke
				(width 0.1)
				(type default)
			)
			(layer "F.Fab")
		)
		(fp_line
			(start -0.12065 0.3048)
			(end -0.67945 0.3048)
			(stroke
				(width 0.1)
				(type default)
			)
			(layer "F.Fab")
		)
		(fp_line
			(start 0.120396 0.2794)
			(end -0.12065 0.2794)
			(stroke
				(width 0.1)
				(type default)
			)
			(layer "F.Fab")
		)
		(fp_line
			(start 0.120396 0.3048)
			(end 0.120396 0.2794)
			(stroke
				(width 0.1)
				(type default)
			)
			(layer "F.Fab")
		)
		(fp_line
			(start 0.12065 -0.3048)
			(end 0.67945 -0.3048)
			(stroke
				(width 0.1)
				(type default)
			)
			(layer "F.Fab")
		)
		(fp_line
			(start 0.12065 -0.2794)
			(end 0.12065 -0.3048)
			(stroke
				(width 0.1)
				(type default)
			)
			(layer "F.Fab")
		)
		(fp_line
			(start 0.67945 -0.3048)
			(end 0.67945 0.3048)
			(stroke
				(width 0.1)
				(type default)
			)
			(layer "F.Fab")
		)
		(fp_line
			(start 0.67945 0.3048)
			(end 0.120396 0.3048)
			(stroke
				(width 0.1)
				(type default)
			)
			(layer "F.Fab")
		)
		(pad "1" smd circle
			(at -0.40005 0)
			(size 0 0)
			(layers "F.Cu" "F.Mask" "F.Paste")
			(net "CLK_GEN2_GPU_FPGA_OE_OR_N")
		)
		(pad "2" smd circle
			(at 0.40005 0)
			(size 0 0)
			(layers "F.Cu" "F.Mask" "F.Paste")
			(net "GND")
		)
	)
	(footprint ""
		(layer "F.Cu")
		(at 252.735842 -92.24137)
		(property "Reference" "R1390"
			(at 0 0 0)
			(layer "F.SilkS")
			(hide yes)
			(effects
				(font
					(size 1.27 1.27)
				)
			)
		)
		(property "Value" ""
			(at 0 0 0)
			(layer "F.Fab")
			(effects
				(font
					(size 1.27 1.27)
				)
			)
		)
		(duplicate_pad_numbers_are_jumpers no)
		(fp_line
			(start -0.7874 -0.4064)
			(end 0.7874 -0.4064)
			(stroke
				(width 0.1524)
				(type default)
			)
			(layer "F.SilkS")
		)
		(fp_line
			(start -0.7874 0.4064)
			(end -0.7874 -0.4064)
			(stroke
				(width 0.1524)
				(type default)
			)
			(layer "F.SilkS")
		)
		(fp_line
			(start 0.7874 -0.4064)
			(end 0.7874 0.4064)
			(stroke
				(width 0.1524)
				(type default)
			)
			(layer "F.SilkS")
		)
		(fp_line
			(start 0.7874 0.4064)
			(end -0.7874 0.4064)
			(stroke
				(width 0.1524)
				(type default)
			)
			(layer "F.SilkS")
		)
		(fp_line
			(start -0.67945 -0.305054)
			(end -0.12065 -0.305054)
			(stroke
				(width 0.1)
				(type default)
			)
			(layer "F.Fab")
		)
		(fp_line
			(start -0.67945 0.3048)
			(end -0.67945 -0.305054)
			(stroke
				(width 0.1)
				(type default)
			)
			(layer "F.Fab")
		)
		(fp_line
			(start -0.12065 -0.305054)
			(end -0.12065 -0.2794)
			(stroke
				(width 0.1)
				(type default)
			)
			(layer "F.Fab")
		)
		(fp_line
			(start -0.12065 -0.2794)
			(end 0.12065 -0.2794)
			(stroke
				(width 0.1)
				(type default)
			)
			(layer "F.Fab")
		)
		(fp_line
			(start -0.12065 0.2794)
			(end -0.12065 0.3048)
			(stroke
				(width 0.1)
				(type default)
			)
			(layer "F.Fab")
		)
		(fp_line
			(start -0.12065 0.3048)
			(end -0.67945 0.3048)
			(stroke
				(width 0.1)
				(type default)
			)
			(layer "F.Fab")
		)
		(fp_line
			(start 0.120396 0.2794)
			(end -0.12065 0.2794)
			(stroke
				(width 0.1)
				(type default)
			)
			(layer "F.Fab")
		)
		(fp_line
			(start 0.120396 0.3048)
			(end 0.120396 0.2794)
			(stroke
				(width 0.1)
				(type default)
			)
			(layer "F.Fab")
		)
		(fp_line
			(start 0.12065 -0.3048)
			(end 0.67945 -0.3048)
			(stroke
				(width 0.1)
				(type default)
			)
			(layer "F.Fab")
		)
		(fp_line
			(start 0.12065 -0.2794)
			(end 0.12065 -0.3048)
			(stroke
				(width 0.1)
				(type default)
			)
			(layer "F.Fab")
		)
		(fp_line
			(start 0.67945 -0.3048)
			(end 0.67945 0.3048)
			(stroke
				(width 0.1)
				(type default)
			)
			(layer "F.Fab")
		)
		(fp_line
			(start 0.67945 0.3048)
			(end 0.120396 0.3048)
			(stroke
				(width 0.1)
				(type default)
			)
			(layer "F.Fab")
		)
		(pad "1" smd circle
			(at -0.40005 0)
			(size 0 0)
			(layers "F.Cu" "F.Mask" "F.Paste")
			(net "FM_PLD_CLKS_DEV_EN")
		)
		(pad "2" smd circle
			(at 0.40005 0)
			(size 0 0)
			(layers "F.Cu" "F.Mask" "F.Paste")
			(net "GND")
		)
	)
)
